(kicad_pcb
	(version 20260206)
	(generator "pcbnew")
	(generator_version "10.0")
	(general
		(thickness 1.6)
		(legacy_teardrops no)
	)
	(paper "A4")
	(title_block
		(title "03242023_DA0F0TMBIJ0_F0T_Motherboard_J_brd_V01_OCP.brd")
		(comment 1 "Grand Teton / footprint 1682 of 6105 (U1), pads 2477-2583 of 4677")
	)
	(layers
		(0 "F.Cu" signal "TOP")
		(4 "In1.Cu" signal "GND")
		(6 "In2.Cu" signal "IN1")
		(8 "In3.Cu" signal "GND1")
		(10 "In4.Cu" signal "IN2")
		(12 "In5.Cu" signal "GND2")
		(14 "In6.Cu" signal "IN3")
		(16 "In7.Cu" signal "GND3")
		(18 "In8.Cu" signal "VCC")
		(20 "In9.Cu" signal "VCC1")
		(22 "In10.Cu" signal "GND4")
		(24 "In11.Cu" signal "IN4")
		(26 "In12.Cu" signal "GND5")
		(28 "In13.Cu" signal "IN5")
		(30 "In14.Cu" signal "GND6")
		(32 "In15.Cu" signal "IN6")
		(34 "In16.Cu" signal "GND7")
		(2 "B.Cu" signal "BOTTOM")
		(9 "F.Adhes" user "F.Adhesive")
		(11 "B.Adhes" user "B.Adhesive")
		(13 "F.Paste" user "Package Geometry/Pastemask Top")
		(15 "B.Paste" user "Package Geometry/Pastemask Bottom")
		(5 "F.SilkS" user "Ref Des/Silkscreen Top")
		(7 "B.SilkS" user "Ref Des/Silkscreen Bottom")
		(1 "F.Mask" user "Board Geometry/Soldermask Top")
		(3 "B.Mask" user "Board Geometry/Soldermask Bottom")
		(17 "Dwgs.User" user "User.Drawings")
		(19 "Cmts.User" user "User.Comments")
		(21 "Eco1.User" user "User.Eco1")
		(23 "Eco2.User" user "User.Eco2")
		(25 "Edge.Cuts" user "Board Geometry/Outline")
		(27 "Margin" user)
		(31 "F.CrtYd" user "Package Geometry/Place Bound Top")
		(29 "B.CrtYd" user "Package Geometry/Place Bound Bottom")
		(35 "F.Fab" user "Ref Des/Assembly Top")
		(33 "B.Fab" user "Ref Des/Assembly Bottom")
	)
	(footprint ""
		(layer "F.Cu")
		(at 111.93018 -251.76988 90)
		(property "Reference" "U1"
			(at -74.913236 41.548812 0)
			(unlocked yes)
			(layer "F.SilkS")
			(effects
				(font
					(size 1.6002 1.1938)
					(thickness 0.1524)
				)
				(justify left)
			)
		)
		(property "Value" ""
			(at 0 0 90)
			(layer "F.Fab")
			(effects
				(font
					(size 1.27 1.27)
				)
			)
		)
		(duplicate_pad_numbers_are_jumpers no)
		(pad "DB85" smd circle
			(at 32.541718 11.097514 270)
			(size 0.4318 0.4318)
			(layers "F.Cu" "F.Mask" "F.Paste")
			(net "P5E_CPU1_PE3_TX_DN<11>")
		)
		(pad "DB87" smd circle
			(at 34.169604 11.097514 270)
			(size 0.4318 0.4318)
			(layers "F.Cu" "F.Mask" "F.Paste")
			(net "GND")
		)
		(pad "DB89" smd circle
			(at 35.797236 11.097514 270)
			(size 0.4318 0.4318)
			(layers "F.Cu" "F.Mask" "F.Paste")
			(net "P5E_CPU1_PE3_RX_DN<12>")
		)
		(pad "DB91" smd oval
			(at 37.425122 11.097514)
			(size 0.381 0.4826)
			(drill
				(offset 0 -0.0508)
			)
			(layers "F.Cu" "F.Mask" "F.Paste")
			(net "GND")
		)
		(pad "DC1" smd oval
			(at -37.425122 11.457686 180)
			(size 0.381 0.4826)
			(drill
				(offset 0 -0.0508)
			)
			(layers "F.Cu" "F.Mask" "F.Paste")
			(net "GND")
		)
		(pad "DC3" smd circle
			(at -35.797236 11.457686 270)
			(size 0.4318 0.4318)
			(layers "F.Cu" "F.Mask" "F.Paste")
			(net "UPI_CPU0_CPU1_P0P1_DP<12>")
		)
		(pad "DC5" smd circle
			(at -34.169604 11.457686 270)
			(size 0.4318 0.4318)
			(layers "F.Cu" "F.Mask" "F.Paste")
			(net "GND")
		)
		(pad "DC7" smd circle
			(at -32.541718 11.457686 270)
			(size 0.4318 0.4318)
			(layers "F.Cu" "F.Mask" "F.Paste")
			(net "UPI_CPU1_CPU0_P1P0_DP<11>")
		)
		(pad "DC9" smd circle
			(at -30.914086 11.457686 270)
			(size 0.4318 0.4318)
			(layers "F.Cu" "F.Mask" "F.Paste")
			(net "GND")
		)
		(pad "DC11" smd circle
			(at -29.2862 11.457686 270)
			(size 0.4318 0.4318)
			(layers "F.Cu" "F.Mask" "F.Paste")
			(net "P5E_CPU1_PE2_RX_DP<3>")
		)
		(pad "DC13" smd circle
			(at -27.658314 11.457686 270)
			(size 0.4318 0.4318)
			(layers "F.Cu" "F.Mask" "F.Paste")
			(net "GND")
		)
		(pad "DC15" smd circle
			(at -26.030682 11.457686 270)
			(size 0.4318 0.4318)
			(layers "F.Cu" "F.Mask" "F.Paste")
			(net "P5E_CPU1_PE2_TX_DP<3>")
		)
		(pad "DC17" smd circle
			(at -24.402796 11.457686 270)
			(size 0.4318 0.4318)
			(layers "F.Cu" "F.Mask" "F.Paste")
			(net "M_H_CPU1_SB_DQ<31>")
		)
		(pad "DC19" smd circle
			(at -22.77491 11.457686 270)
			(size 0.4318 0.4318)
			(layers "F.Cu" "F.Mask" "F.Paste")
			(net "M_H_CPU1_SB_DQ<25>")
		)
		(pad "DC21" smd circle
			(at -21.147278 11.457686 270)
			(size 0.4318 0.4318)
			(layers "F.Cu" "F.Mask" "F.Paste")
			(net "GND")
		)
		(pad "DC23" smd circle
			(at -19.519392 11.457686 270)
			(size 0.4318 0.4318)
			(layers "F.Cu" "F.Mask" "F.Paste")
			(net "M_H_CPU1_SB_DQ<12>")
		)
		(pad "DC25" smd circle
			(at -17.89176 11.457686 270)
			(size 0.4318 0.4318)
			(layers "F.Cu" "F.Mask" "F.Paste")
			(net "M_H_CPU1_SB_DQ<9>")
		)
		(pad "DC27" smd circle
			(at -16.263874 11.457686 270)
			(size 0.4318 0.4318)
			(layers "F.Cu" "F.Mask" "F.Paste")
			(net "GND")
		)
		(pad "DC29" smd circle
			(at -14.635988 11.457686 270)
			(size 0.4318 0.4318)
			(layers "F.Cu" "F.Mask" "F.Paste")
			(net "M_H_CPU1_SB_DQ<4>")
		)
		(pad "DC31" smd circle
			(at -13.008356 11.457686 270)
			(size 0.4318 0.4318)
			(layers "F.Cu" "F.Mask" "F.Paste")
			(net "M_H_CPU1_SB_DQ<1>")
		)
		(pad "DC33" smd circle
			(at -11.380724 11.457686 270)
			(size 0.4318 0.4318)
			(layers "F.Cu" "F.Mask" "F.Paste")
			(net "GND")
		)
		(pad "DC35" smd circle
			(at -9.752838 11.457686 270)
			(size 0.4318 0.4318)
			(layers "F.Cu" "F.Mask" "F.Paste")
			(net "M_H_CPU1_SB_CB<0>")
		)
		(pad "DC37" smd circle
			(at -8.124952 11.457686 270)
			(size 0.4318 0.4318)
			(layers "F.Cu" "F.Mask" "F.Paste")
			(net "M_H_CPU1_SB_CB<7>")
		)
		(pad "DC39" smd circle
			(at -6.49732 11.457686 270)
			(size 0.4318 0.4318)
			(layers "F.Cu" "F.Mask" "F.Paste")
			(net "GND")
		)
		(pad "DC41" smd circle
			(at -4.869434 11.457686 270)
			(size 0.4318 0.4318)
			(layers "F.Cu" "F.Mask" "F.Paste")
			(net "M_H_CPU1_SA_CA<6>")
		)
		(pad "DC43" smd circle
			(at -3.241802 11.457686 270)
			(size 0.4318 0.4318)
			(layers "F.Cu" "F.Mask" "F.Paste")
			(net "M_E_CPU1_SA_RSP<1>")
		)
		(pad "DC45" smd circle
			(at -1.613916 11.457686 270)
			(size 0.4318 0.4318)
			(layers "F.Cu" "F.Mask" "F.Paste")
			(net "GND")
		)
		(pad "DC48" smd circle
			(at 2.427732 11.567668 270)
			(size 0.4318 0.4318)
			(layers "F.Cu" "F.Mask" "F.Paste")
			(net "M_H_CPU1_SA_CA<2>")
		)
		(pad "DC50" smd circle
			(at 4.055618 11.567668 270)
			(size 0.4318 0.4318)
			(layers "F.Cu" "F.Mask" "F.Paste")
			(net "M_H_CPU1_SA_CS_N<3>")
		)
		(pad "DC52" smd circle
			(at 5.68325 11.567668 270)
			(size 0.4318 0.4318)
			(layers "F.Cu" "F.Mask" "F.Paste")
			(net "GND")
		)
		(pad "DC54" smd circle
			(at 7.311136 11.567668 270)
			(size 0.4318 0.4318)
			(layers "F.Cu" "F.Mask" "F.Paste")
			(net "M_H_CPU1_SA_CB<4>")
		)
		(pad "DC56" smd circle
			(at 8.939022 11.567668 270)
			(size 0.4318 0.4318)
			(layers "F.Cu" "F.Mask" "F.Paste")
			(net "M_H_CPU1_SA_CB<1>")
		)
		(pad "DC58" smd circle
			(at 10.566654 11.567668 270)
			(size 0.4318 0.4318)
			(layers "F.Cu" "F.Mask" "F.Paste")
			(net "GND")
		)
		(pad "DC60" smd circle
			(at 12.19454 11.567668 270)
			(size 0.4318 0.4318)
			(layers "F.Cu" "F.Mask" "F.Paste")
			(net "M_H_CPU1_SA_DQ<28>")
		)
		(pad "DC62" smd circle
			(at 13.822426 11.567668 270)
			(size 0.4318 0.4318)
			(layers "F.Cu" "F.Mask" "F.Paste")
			(net "M_H_CPU1_SA_DQ<25>")
		)
		(pad "DC64" smd circle
			(at 15.450058 11.567668 270)
			(size 0.4318 0.4318)
			(layers "F.Cu" "F.Mask" "F.Paste")
			(net "GND")
		)
		(pad "DC66" smd circle
			(at 17.07769 11.567668 270)
			(size 0.4318 0.4318)
			(layers "F.Cu" "F.Mask" "F.Paste")
			(net "M_H_CPU1_SA_DQ<20>")
		)
		(pad "DC68" smd circle
			(at 18.705576 11.567668 270)
			(size 0.4318 0.4318)
			(layers "F.Cu" "F.Mask" "F.Paste")
			(net "M_H_CPU1_SA_DQ<17>")
		)
		(pad "DC70" smd circle
			(at 20.333462 11.567668 270)
			(size 0.4318 0.4318)
			(layers "F.Cu" "F.Mask" "F.Paste")
			(net "GND")
		)
		(pad "DC72" smd circle
			(at 21.961094 11.567668 270)
			(size 0.4318 0.4318)
			(layers "F.Cu" "F.Mask" "F.Paste")
			(net "M_H_CPU1_SA_DQ<12>")
		)
		(pad "DC74" smd circle
			(at 23.58898 11.567668 270)
			(size 0.4318 0.4318)
			(layers "F.Cu" "F.Mask" "F.Paste")
			(net "M_H_CPU1_SA_DQ<9>")
		)
		(pad "DC76" smd circle
			(at 25.216612 11.567668 270)
			(size 0.4318 0.4318)
			(layers "F.Cu" "F.Mask" "F.Paste")
			(net "GND")
		)
		(pad "DC78" smd circle
			(at 26.844498 11.567668 270)
			(size 0.4318 0.4318)
			(layers "F.Cu" "F.Mask" "F.Paste")
			(net "GND")
		)
		(pad "DC80" smd circle
			(at 28.472384 11.567668 270)
			(size 0.4318 0.4318)
			(layers "F.Cu" "F.Mask" "F.Paste")
			(net "GND")
		)
		(pad "DC82" smd circle
			(at 30.100016 11.567668 270)
			(size 0.4318 0.4318)
			(layers "F.Cu" "F.Mask" "F.Paste")
			(net "GND")
		)
		(pad "DC84" smd circle
			(at 31.727902 11.567668 270)
			(size 0.4318 0.4318)
			(layers "F.Cu" "F.Mask" "F.Paste")
			(net "GND")
		)
		(pad "DC86" smd circle
			(at 33.355534 11.567668 270)
			(size 0.4318 0.4318)
			(layers "F.Cu" "F.Mask" "F.Paste")
			(net "P5E_CPU1_PE3_TX_DP<11>")
		)
		(pad "DC88" smd circle
			(at 34.98342 11.567668 270)
			(size 0.4318 0.4318)
			(layers "F.Cu" "F.Mask" "F.Paste")
			(net "GND")
		)
		(pad "DC90" smd circle
			(at 36.611306 11.567668 270)
			(size 0.4318 0.4318)
			(layers "F.Cu" "F.Mask" "F.Paste")
			(net "P5E_CPU1_PE3_RX_DP<12>")
		)
		(pad "DD2" smd circle
			(at -36.611306 11.927332 270)
			(size 0.4318 0.4318)
			(layers "F.Cu" "F.Mask" "F.Paste")
			(net "UPI_CPU0_CPU1_P0P1_DN<12>")
		)
		(pad "DD4" smd circle
			(at -34.98342 11.927332 270)
			(size 0.4318 0.4318)
			(layers "F.Cu" "F.Mask" "F.Paste")
			(net "GND")
		)
		(pad "DD6" smd circle
			(at -33.355534 11.927332 270)
			(size 0.4318 0.4318)
			(layers "F.Cu" "F.Mask" "F.Paste")
			(net "UPI_CPU1_CPU0_P1P0_DN<11>")
		)
		(pad "DD8" smd circle
			(at -31.727902 11.927332 270)
			(size 0.4318 0.4318)
			(layers "F.Cu" "F.Mask" "F.Paste")
			(net "GND")
		)
		(pad "DD10" smd circle
			(at -30.100016 11.927332 270)
			(size 0.4318 0.4318)
			(layers "F.Cu" "F.Mask" "F.Paste")
			(net "P5E_CPU1_PE2_RX_DN<3>")
		)
		(pad "DD12" smd circle
			(at -28.472384 11.927332 270)
			(size 0.4318 0.4318)
			(layers "F.Cu" "F.Mask" "F.Paste")
			(net "GND")
		)
		(pad "DD14" smd circle
			(at -26.844498 11.927332 270)
			(size 0.4318 0.4318)
			(layers "F.Cu" "F.Mask" "F.Paste")
			(net "P5E_CPU1_PE2_TX_DP<4>")
		)
		(pad "DD16" smd circle
			(at -25.216612 11.927332 270)
			(size 0.4318 0.4318)
			(layers "F.Cu" "F.Mask" "F.Paste")
			(net "GND")
		)
		(pad "DD18" smd circle
			(at -23.58898 11.927332 270)
			(size 0.4318 0.4318)
			(layers "F.Cu" "F.Mask" "F.Paste")
			(net "M_H_CPU1_SB_DQS_DP<3>")
		)
		(pad "DD20" smd circle
			(at -21.961094 11.927332 270)
			(size 0.4318 0.4318)
			(layers "F.Cu" "F.Mask" "F.Paste")
			(net "M_H_CPU1_SB_DQ<24>")
		)
		(pad "DD22" smd circle
			(at -20.333462 11.927332 270)
			(size 0.4318 0.4318)
			(layers "F.Cu" "F.Mask" "F.Paste")
			(net "M_H_CPU1_SB_DQ<13>")
		)
		(pad "DD24" smd circle
			(at -18.705576 11.927332 270)
			(size 0.4318 0.4318)
			(layers "F.Cu" "F.Mask" "F.Paste")
			(net "M_H_CPU1_SB_DQS_DN<1>")
		)
		(pad "DD26" smd circle
			(at -17.07769 11.927332 270)
			(size 0.4318 0.4318)
			(layers "F.Cu" "F.Mask" "F.Paste")
			(net "M_H_CPU1_SB_DQ<8>")
		)
		(pad "DD28" smd circle
			(at -15.450058 11.927332 270)
			(size 0.4318 0.4318)
			(layers "F.Cu" "F.Mask" "F.Paste")
			(net "M_H_CPU1_SB_DQ<7>")
		)
		(pad "DD30" smd circle
			(at -13.822426 11.927332 270)
			(size 0.4318 0.4318)
			(layers "F.Cu" "F.Mask" "F.Paste")
			(net "M_H_CPU1_SB_DQS_DN<0>")
		)
		(pad "DD32" smd circle
			(at -12.19454 11.927332 270)
			(size 0.4318 0.4318)
			(layers "F.Cu" "F.Mask" "F.Paste")
			(net "M_H_CPU1_SB_DQ<0>")
		)
		(pad "DD34" smd circle
			(at -10.566654 11.927332 270)
			(size 0.4318 0.4318)
			(layers "F.Cu" "F.Mask" "F.Paste")
			(net "M_H_CPU1_SB_CB<1>")
		)
		(pad "DD36" smd circle
			(at -8.939022 11.927332 270)
			(size 0.4318 0.4318)
			(layers "F.Cu" "F.Mask" "F.Paste")
			(net "M_H_CPU1_SB_DQS_DN<9>")
		)
		(pad "DD38" smd circle
			(at -7.311136 11.927332 270)
			(size 0.4318 0.4318)
			(layers "F.Cu" "F.Mask" "F.Paste")
			(net "M_H_CPU1_SB_CB<6>")
		)
		(pad "DD40" smd circle
			(at -5.68325 11.927332 270)
			(size 0.4318 0.4318)
			(layers "F.Cu" "F.Mask" "F.Paste")
			(net "M_H_CPU1_SA_PAR")
		)
		(pad "DD42" smd circle
			(at -4.055618 11.927332 270)
			(size 0.4318 0.4318)
			(layers "F.Cu" "F.Mask" "F.Paste")
			(net "M_H_CPU1_CLK_DN<1>")
		)
		(pad "DD44" smd circle
			(at -2.427732 11.927332 270)
			(size 0.4318 0.4318)
			(layers "F.Cu" "F.Mask" "F.Paste")
			(net "M_E_CPU1_SA_RSP<0>")
		)
		(pad "DD47" smd circle
			(at 1.613916 12.037314 270)
			(size 0.4318 0.4318)
			(layers "F.Cu" "F.Mask" "F.Paste")
			(net "M_H_CPU1_SA_CA<4>")
		)
		(pad "DD49" smd circle
			(at 3.241802 12.037314 270)
			(size 0.4318 0.4318)
			(layers "F.Cu" "F.Mask" "F.Paste")
			(net "GND")
		)
		(pad "DD51" smd circle
			(at 4.869434 12.037314 270)
			(size 0.4318 0.4318)
			(layers "F.Cu" "F.Mask" "F.Paste")
			(net "M_H_CPU1_SA_CS_N<2>")
		)
		(pad "DD53" smd circle
			(at 6.49732 12.037314 270)
			(size 0.4318 0.4318)
			(layers "F.Cu" "F.Mask" "F.Paste")
			(net "M_H_CPU1_SA_CB<5>")
		)
		(pad "DD55" smd circle
			(at 8.124952 12.037314 270)
			(size 0.4318 0.4318)
			(layers "F.Cu" "F.Mask" "F.Paste")
			(net "M_H_CPU1_SA_DQS_DN<4>")
		)
		(pad "DD57" smd circle
			(at 9.752838 12.037314 270)
			(size 0.4318 0.4318)
			(layers "F.Cu" "F.Mask" "F.Paste")
			(net "M_H_CPU1_SA_CB<0>")
		)
		(pad "DD59" smd circle
			(at 11.380724 12.037314 270)
			(size 0.4318 0.4318)
			(layers "F.Cu" "F.Mask" "F.Paste")
			(net "M_H_CPU1_SA_DQ<29>")
		)
		(pad "DD61" smd circle
			(at 13.008356 12.037314 270)
			(size 0.4318 0.4318)
			(layers "F.Cu" "F.Mask" "F.Paste")
			(net "M_H_CPU1_SA_DQS_DN<3>")
		)
		(pad "DD63" smd circle
			(at 14.635988 12.037314 270)
			(size 0.4318 0.4318)
			(layers "F.Cu" "F.Mask" "F.Paste")
			(net "M_H_CPU1_SA_DQ<24>")
		)
		(pad "DD65" smd circle
			(at 16.263874 12.037314 270)
			(size 0.4318 0.4318)
			(layers "F.Cu" "F.Mask" "F.Paste")
			(net "M_H_CPU1_SA_DQ<21>")
		)
		(pad "DD67" smd circle
			(at 17.89176 12.037314 270)
			(size 0.4318 0.4318)
			(layers "F.Cu" "F.Mask" "F.Paste")
			(net "M_H_CPU1_SA_DQS_DN<2>")
		)
		(pad "DD69" smd circle
			(at 19.519392 12.037314 270)
			(size 0.4318 0.4318)
			(layers "F.Cu" "F.Mask" "F.Paste")
			(net "M_H_CPU1_SA_DQ<16>")
		)
		(pad "DD71" smd circle
			(at 21.147278 12.037314 270)
			(size 0.4318 0.4318)
			(layers "F.Cu" "F.Mask" "F.Paste")
			(net "M_H_CPU1_SA_DQ<13>")
		)
		(pad "DD73" smd circle
			(at 22.77491 12.037314 270)
			(size 0.4318 0.4318)
			(layers "F.Cu" "F.Mask" "F.Paste")
			(net "M_H_CPU1_SA_DQS_DP<1>")
		)
		(pad "DD75" smd circle
			(at 24.402796 12.037314 270)
			(size 0.4318 0.4318)
			(layers "F.Cu" "F.Mask" "F.Paste")
			(net "M_H_CPU1_SA_DQ<8>")
		)
		(pad "DD77" smd circle
			(at 26.030682 12.037314 270)
			(size 0.4318 0.4318)
			(layers "F.Cu" "F.Mask" "F.Paste")
			(net "PVCCFA_EHV_FIVRA_CPU1")
		)
		(pad "DD79" smd circle
			(at 27.658314 12.037314 270)
			(size 0.4318 0.4318)
			(layers "F.Cu" "F.Mask" "F.Paste")
			(net "GND")
		)
		(pad "DD81" smd circle
			(at 29.2862 12.037314 270)
			(size 0.4318 0.4318)
			(layers "F.Cu" "F.Mask" "F.Paste")
			(net "GND")
		)
		(pad "DD83" smd circle
			(at 30.914086 12.037314 270)
			(size 0.4318 0.4318)
			(layers "F.Cu" "F.Mask" "F.Paste")
			(net "PVCCFA_EHV_FIVRA_CPU1")
		)
		(pad "DD85" smd circle
			(at 32.541718 12.037314 270)
			(size 0.4318 0.4318)
			(layers "F.Cu" "F.Mask" "F.Paste")
			(net "PVCCFA_EHV_FIVRA_CPU1")
		)
		(pad "DD87" smd circle
			(at 34.169604 12.037314 270)
			(size 0.4318 0.4318)
			(layers "F.Cu" "F.Mask" "F.Paste")
			(net "P5E_CPU1_PE3_TX_DN<10>")
		)
		(pad "DD89" smd circle
			(at 35.797236 12.037314 270)
			(size 0.4318 0.4318)
			(layers "F.Cu" "F.Mask" "F.Paste")
			(net "PVCCFA_EHV_FIVRA_CPU1")
		)
		(pad "DD91" smd oval
			(at 37.425122 12.037314)
			(size 0.381 0.4826)
			(drill
				(offset 0 -0.0508)
			)
			(layers "F.Cu" "F.Mask" "F.Paste")
			(net "P5E_CPU1_PE3_RX_DN<11>")
		)
		(pad "DE1" smd oval
			(at -37.425122 12.397486 180)
			(size 0.381 0.4826)
			(drill
				(offset 0 -0.0508)
			)
			(layers "F.Cu" "F.Mask" "F.Paste")
			(net "UPI_CPU0_CPU1_P0P1_DN<11>")
		)
		(pad "DE3" smd circle
			(at -35.797236 12.397486 270)
			(size 0.4318 0.4318)
			(layers "F.Cu" "F.Mask" "F.Paste")
			(net "PVCCINFAON_CPU1")
		)
		(pad "DE5" smd circle
			(at -34.169604 12.397486 270)
			(size 0.4318 0.4318)
			(layers "F.Cu" "F.Mask" "F.Paste")
			(net "UPI_CPU1_CPU0_P1P0_DN<10>")
		)
		(pad "DE7" smd circle
			(at -32.541718 12.397486 270)
			(size 0.4318 0.4318)
			(layers "F.Cu" "F.Mask" "F.Paste")
			(net "PVCCINFAON_CPU1")
		)
		(pad "DE9" smd circle
			(at -30.914086 12.397486 270)
			(size 0.4318 0.4318)
			(layers "F.Cu" "F.Mask" "F.Paste")
			(net "P5E_CPU1_PE2_RX_DN<4>")
		)
		(pad "DE11" smd circle
			(at -29.2862 12.397486 270)
			(size 0.4318 0.4318)
			(layers "F.Cu" "F.Mask" "F.Paste")
			(net "PVCCINFAON_CPU1")
		)
		(pad "DE13" smd circle
			(at -27.658314 12.397486 270)
			(size 0.4318 0.4318)
			(layers "F.Cu" "F.Mask" "F.Paste")
			(net "P5E_CPU1_PE2_TX_DN<4>")
		)
		(pad "DE15" smd circle
			(at -26.030682 12.397486 270)
			(size 0.4318 0.4318)
			(layers "F.Cu" "F.Mask" "F.Paste")
			(net "PVCCINFAON_CPU1")
		)
		(pad "DE17" smd circle
			(at -24.402796 12.397486 270)
			(size 0.4318 0.4318)
			(layers "F.Cu" "F.Mask" "F.Paste")
			(net "GND")
		)
		(pad "DE19" smd circle
			(at -22.77491 12.397486 270)
			(size 0.4318 0.4318)
			(layers "F.Cu" "F.Mask" "F.Paste")
			(net "GND")
		)
		(pad "DE21" smd circle
			(at -21.147278 12.397486 270)
			(size 0.4318 0.4318)
			(layers "F.Cu" "F.Mask" "F.Paste")
			(net "GND")
		)
		(pad "DE23" smd circle
			(at -19.519392 12.397486 270)
			(size 0.4318 0.4318)
			(layers "F.Cu" "F.Mask" "F.Paste")
			(net "GND")
		)
		(pad "DE25" smd circle
			(at -17.89176 12.397486 270)
			(size 0.4318 0.4318)
			(layers "F.Cu" "F.Mask" "F.Paste")
			(net "GND")
		)
	)
)
